# BASEBOARD_FAB2 (Tioga Pass) — schematic netlist excerpt (pin names and nets, part order shuffled) for the footprints in the layout excerpt that follows; sources: Cadence DE-HDL packaged netlist, KiCad conversion of Wiwynn_Tioga_Pass_MB.brd

C3D9  CAP_A  22.0UF 4V 20% X6S  pkg 0603V  page 76 : A = PVCCIO_CPU1 ; B = GND
C4D11  CAP_A  0.1UF 16V 10% X7R  pkg 0402V  page 203 : A = VR_FET_SW_P12V_STBY_PVCCIN_CPU0 ; B = GND

U9A4  TC7PZ14FU-GP  pkg DISCRET-GA1  page 175
  \1a\  = FP_PWR_BTN_R1_N
  GND  = GND
  \2a\  = FP_PWR_BTN_BUF1_N
  \2y\  = FM_PWR_BTN_R_N
  VCC  = P3V3_STBY
  \1y\  = FP_PWR_BTN_BUF1_N

(kicad_pcb
	(version 20260206)
	(generator "pcbnew")
	(generator_version "10.0")
	(general
		(thickness 1.6)
		(legacy_teardrops no)
	)
	(paper "A4")
	(title_block
		(title "Wiwynn_Tioga_Pass_MB.brd")
		(comment 1 "Tioga Pass / footprints 228-230 of 4770")
	)
	(layers
		(0 "F.Cu" signal "TOP")
		(4 "In1.Cu" signal "L2GND")
		(6 "In2.Cu" signal "L3")
		(8 "In3.Cu" signal "L4GND")
		(10 "In4.Cu" signal "L5")
		(12 "In5.Cu" signal "L6GND")
		(14 "In6.Cu" signal "L7VCC")
		(16 "In7.Cu" signal "L8VCC")
		(18 "In8.Cu" signal "L9GND")
		(20 "In9.Cu" signal "L10")
		(22 "In10.Cu" signal "L11GND")
		(24 "In11.Cu" signal "L12")
		(26 "In12.Cu" signal "L13GND")
		(2 "B.Cu" signal "BOTTOM")
		(9 "F.Adhes" user "F.Adhesive")
		(11 "B.Adhes" user "B.Adhesive")
		(13 "F.Paste" user "Package Geometry/Pastemask Top")
		(15 "B.Paste" user "Package Geometry/Pastemask Bottom")
		(5 "F.SilkS" user "Ref Des/Silkscreen Top")
		(7 "B.SilkS" user "Ref Des/Silkscreen Bottom")
		(1 "F.Mask" user "Board Geometry/Soldermask Top")
		(3 "B.Mask" user "Board Geometry/Soldermask Bottom")
		(17 "Dwgs.User" user "User.Drawings")
		(19 "Cmts.User" user "User.Comments")
		(21 "Eco1.User" user "User.Eco1")
		(23 "Eco2.User" user "User.Eco2")
		(25 "Edge.Cuts" user "Board Geometry/Outline")
		(27 "Margin" user)
		(31 "F.CrtYd" user "Package Geometry/Place Bound Top")
		(29 "B.CrtYd" user "Package Geometry/Place Bound Bottom")
		(35 "F.Fab" user "Ref Des/Assembly Top")
		(33 "B.Fab" user "Ref Des/Assembly Bottom")
	)
	(footprint ""
		(layer "F.Cu")
		(at 479.2218 -140.8684 90)
		(property "Reference" "U9A4"
			(at 0 0 90)
			(layer "F.SilkS")
			(hide yes)
			(effects
				(font
					(size 1.27 1.27)
				)
			)
		)
		(property "Value" "*"
			(at -2.3622 -8.3185 90)
			(unlocked yes)
			(layer "F.Fab")
			(hide yes)
			(effects
				(font
					(size 1.27 1.016)
					(thickness 0.1524)
				)
			)
		)
		(property "Device Type" "TC7PZ14FU-GP_DISCRET-GA1-TC7PZA"
			(at -2.3622 -10.2235 90)
			(unlocked yes)
			(layer "F.Fab")
			(hide yes)
			(effects
				(font
					(size 1.27 1.016)
					(thickness 0.1524)
				)
			)
		)
		(duplicate_pad_numbers_are_jumpers no)
		(fp_line
			(start 1.4478 -1.7018)
			(end -1.4478 -1.7018)
			(stroke
				(width 0.1524)
				(type default)
			)
			(layer "F.SilkS")
		)
		(fp_line
			(start -1.4478 -1.7018)
			(end -1.4478 1.7018)
			(stroke
				(width 0.1524)
				(type default)
			)
			(layer "F.SilkS")
		)
		(fp_line
			(start 1.4478 1.7018)
			(end 1.4478 -1.7018)
			(stroke
				(width 0.1524)
				(type default)
			)
			(layer "F.SilkS")
		)
		(fp_line
			(start -1.4478 1.7018)
			(end 1.4478 1.7018)
			(stroke
				(width 0.1524)
				(type default)
			)
			(layer "F.SilkS")
		)
		(fp_line
			(start -0.5715 1.7907)
			(end -1.5494 1.7907)
			(stroke
				(width 0.3302)
				(type default)
			)
			(layer "F.SilkS")
		)
		(fp_line
			(start -1.5494 1.7907)
			(end -1.5494 0.8255)
			(stroke
				(width 0.3302)
				(type default)
			)
			(layer "F.SilkS")
		)
		(fp_poly
			(pts
				(xy -0.6604 1.7272) (xy -1.016 2.0828) (xy -0.3048 2.0828)
			)
			(stroke
				(width 0)
				(type default)
			)
			(fill yes)
			(layer "F.SilkS")
		)
		(fp_poly
			(pts
				(xy -1.524 -1.778) (xy 1.524 -1.778) (xy 1.524 1.778) (xy -1.524 1.778)
			)
			(stroke
				(width 0)
				(type default)
			)
			(fill no)
			(layer "F.CrtYd")
		)
		(fp_poly
			(pts
				(xy -1.524 -1.778) (xy 1.524 -1.778) (xy 1.524 1.778) (xy -1.524 1.778)
			)
			(stroke
				(width 0)
				(type default)
			)
			(fill no)
			(layer "F.Fab")
		)
		(pad "1" smd rect
			(at -0.65024 0.9398 90)
			(size 0.4064 1.016)
			(layers "F.Cu" "F.Mask" "F.Paste")
			(net "FP_PWR_BTN_R1_N")
		)
		(pad "2" smd rect
			(at 0 0.9398 90)
			(size 0.4064 1.016)
			(layers "F.Cu" "F.Mask" "F.Paste")
			(net "GND")
		)
		(pad "3" smd rect
			(at 0.65024 0.9398 90)
			(size 0.4064 1.016)
			(layers "F.Cu" "F.Mask" "F.Paste")
			(net "FP_PWR_BTN_BUF1_N")
		)
		(pad "4" smd rect
			(at 0.65024 -0.9398 90)
			(size 0.4064 1.016)
			(layers "F.Cu" "F.Mask" "F.Paste")
			(net "FM_PWR_BTN_R_N")
		)
		(pad "5" smd rect
			(at 0 -0.9398 90)
			(size 0.4064 1.016)
			(layers "F.Cu" "F.Mask" "F.Paste")
			(net "P3V3_STBY")
		)
		(pad "6" smd rect
			(at -0.65024 -0.9398 90)
			(size 0.4064 1.016)
			(layers "F.Cu" "F.Mask" "F.Paste")
			(net "FP_PWR_BTN_BUF1_N")
		)
	)
	(footprint ""
		(layer "F.Cu")
		(at 114.602768 -79.6036 180)
		(property "Reference" "C3D9"
			(at 0 0 180)
			(layer "F.SilkS")
			(hide yes)
			(effects
				(font
					(size 1.27 1.27)
				)
			)
		)
		(property "Value" ""
			(at 0 0 180)
			(layer "F.Fab")
			(effects
				(font
					(size 1.27 1.27)
				)
			)
		)
		(duplicate_pad_numbers_are_jumpers no)
		(fp_poly
			(pts
				(xy -0.4953 -0.2032) (xy 0.4953 -0.2032) (xy 0.4953 1.6002) (xy -0.4953 1.6002)
			)
			(stroke
				(width 0)
				(type default)
			)
			(fill no)
			(layer "F.CrtYd")
		)
		(fp_line
			(start 0.4953 1.6002)
			(end -0.4953 1.6002)
			(stroke
				(width 0.1)
				(type default)
			)
			(layer "F.Fab")
		)
		(fp_line
			(start 0.4953 -0.2032)
			(end 0.4953 1.6002)
			(stroke
				(width 0.1)
				(type default)
			)
			(layer "F.Fab")
		)
		(fp_line
			(start -0.4953 1.6002)
			(end -0.4953 -0.2032)
			(stroke
				(width 0.1)
				(type default)
			)
			(layer "F.Fab")
		)
		(fp_line
			(start -0.4953 -0.2032)
			(end 0.4953 -0.2032)
			(stroke
				(width 0.1)
				(type default)
			)
			(layer "F.Fab")
		)
		(pad "1" smd rect
			(at 0 0 180)
			(size 0.762 0.889)
			(layers "F.Cu" "F.Mask" "F.Paste")
			(net "PVCCIO_CPU1")
		)
		(pad "2" smd rect
			(at 0 1.397 180)
			(size 0.762 0.889)
			(layers "F.Cu" "F.Mask" "F.Paste")
			(net "GND")
		)
		(zone
			(layer "F.Cu")
			(hatch none 0.5)
			(connect_pads
				(clearance 0)
			)
			(min_thickness 0.25)
			(keepout
				(tracks not_allowed)
				(vias allowed)
				(pads allowed)
				(copperpour not_allowed)
				(footprints allowed)
			)
			(placement
				(enabled no)
				(sheetname "")
			)
			(fill
				(thermal_gap 0.5)
				(thermal_bridge_width 0.5)
				(island_removal_mode 0)
			)
			(polygon
				(pts
					(xy 114.983768 -80.0481) (xy 114.221768 -80.0481) (xy 114.221768 -80.5561) (xy 114.983768 -80.5561)
				)
			)
		)
	)
	(footprint ""
		(layer "F.Cu")
		(at 198.44131 -84.847684 90)
		(property "Reference" "C4D11"
			(at 0 0 90)
			(layer "F.SilkS")
			(hide yes)
			(effects
				(font
					(size 1.27 1.27)
				)
			)
		)
		(property "Value" ""
			(at 0 0 90)
			(layer "F.Fab")
			(effects
				(font
					(size 1.27 1.27)
				)
			)
		)
		(duplicate_pad_numbers_are_jumpers no)
		(fp_rect
			(start 0.3048 0.9906)
			(end -0.3048 -0.1016)
			(stroke
				(width 0)
				(type default)
			)
			(fill no)
			(layer "F.CrtYd")
		)
		(fp_line
			(start 0.3048 -0.1016)
			(end -0.3048 -0.1016)
			(stroke
				(width 0.1)
				(type default)
			)
			(layer "F.Fab")
		)
		(fp_line
			(start -0.3048 -0.1016)
			(end -0.3048 0.9906)
			(stroke
				(width 0.1)
				(type default)
			)
			(layer "F.Fab")
		)
		(fp_line
			(start 0.3048 0.9906)
			(end 0.3048 -0.1016)
			(stroke
				(width 0.1)
				(type default)
			)
			(layer "F.Fab")
		)
		(fp_line
			(start -0.3048 0.9906)
			(end 0.3048 0.9906)
			(stroke
				(width 0.1)
				(type default)
			)
			(layer "F.Fab")
		)
		(pad "1" smd rect
			(at 0 0 90)
			(size 0.508 0.508)
			(layers "F.Cu" "F.Mask" "F.Paste")
			(net "VR_FET_SW_P12V_STBY_PVCCIN_CPU0")
		)
		(pad "2" smd rect
			(at 0 0.889 90)
			(size 0.508 0.508)
			(layers "F.Cu" "F.Mask" "F.Paste")
			(net "GND")
		)
		(zone
			(layer "F.Cu")
			(hatch none 0.5)
			(connect_pads
				(clearance 0)
			)
			(min_thickness 0.25)
			(keepout
				(tracks not_allowed)
				(vias allowed)
				(pads allowed)
				(copperpour not_allowed)
				(footprints allowed)
			)
			(placement
				(enabled no)
				(sheetname "")
			)
			(fill
				(thermal_gap 0.5)
				(thermal_bridge_width 0.5)
				(island_removal_mode 0)
			)
			(polygon
				(pts
					(xy 199.07631 -85.101684) (xy 198.69531 -85.101684) (xy 198.69531 -84.593684) (xy 199.07631 -84.593684)
				)
			)
		)
		(zone
			(layer "F.Cu")
			(hatch none 0.5)
			(connect_pads
				(clearance 0)
			)
			(min_thickness 0.25)
			(keepout
				(tracks allowed)
				(vias not_allowed)
				(pads allowed)
				(copperpour not_allowed)
				(footprints allowed)
			)
			(placement
				(enabled no)
				(sheetname "")
			)
			(fill
				(thermal_gap 0.5)
				(thermal_bridge_width 0.5)
				(island_removal_mode 0)
			)
			(polygon
				(pts
					(xy 199.07631 -85.101684) (xy 198.69531 -85.101684) (xy 198.69531 -84.593684) (xy 199.07631 -84.593684)
				)
			)
		)
	)
)
